# BASEBOARD_FAB2 (Tioga Pass) — schematic netlist excerpt (pin names and nets, part order shuffled) for the footprints in the layout excerpt that follows; sources: Cadence DE-HDL packaged netlist, KiCad conversion of Wiwynn_Tioga_Pass_MB.brd

R2T60  RES  0.0 5% CHIP  pkg 0402  page 93 : A = H_CPU0_PROCHOT_G_N ; B = H_CPU0_PROCHOT_G_R_N
R2U38  RES  665 1.0% CHIP  pkg 0402  page 167 : A = P3V3_STBY ; B = SMB_SENSOR_STBY_LVC3_SCL

(kicad_pcb
	(version 20260206)
	(generator "pcbnew")
	(generator_version "10.0")
	(general
		(thickness 1.6)
		(legacy_teardrops no)
	)
	(paper "A4")
	(title_block
		(title "Wiwynn_Tioga_Pass_MB.brd")
		(comment 1 "Tioga Pass / footprints 2443-2444 of 4770")
	)
	(layers
		(0 "F.Cu" signal "TOP")
		(4 "In1.Cu" signal "L2GND")
		(6 "In2.Cu" signal "L3")
		(8 "In3.Cu" signal "L4GND")
		(10 "In4.Cu" signal "L5")
		(12 "In5.Cu" signal "L6GND")
		(14 "In6.Cu" signal "L7VCC")
		(16 "In7.Cu" signal "L8VCC")
		(18 "In8.Cu" signal "L9GND")
		(20 "In9.Cu" signal "L10")
		(22 "In10.Cu" signal "L11GND")
		(24 "In11.Cu" signal "L12")
		(26 "In12.Cu" signal "L13GND")
		(2 "B.Cu" signal "BOTTOM")
		(9 "F.Adhes" user "F.Adhesive")
		(11 "B.Adhes" user "B.Adhesive")
		(13 "F.Paste" user "Package Geometry/Pastemask Top")
		(15 "B.Paste" user "Package Geometry/Pastemask Bottom")
		(5 "F.SilkS" user "Ref Des/Silkscreen Top")
		(7 "B.SilkS" user "Ref Des/Silkscreen Bottom")
		(1 "F.Mask" user "Board Geometry/Soldermask Top")
		(3 "B.Mask" user "Board Geometry/Soldermask Bottom")
		(17 "Dwgs.User" user "User.Drawings")
		(19 "Cmts.User" user "User.Comments")
		(21 "Eco1.User" user "User.Eco1")
		(23 "Eco2.User" user "User.Eco2")
		(25 "Edge.Cuts" user "Board Geometry/Outline")
		(27 "Margin" user)
		(31 "F.CrtYd" user "Package Geometry/Place Bound Top")
		(29 "B.CrtYd" user "Package Geometry/Place Bound Bottom")
		(35 "F.Fab" user "Ref Des/Assembly Top")
		(33 "B.Fab" user "Ref Des/Assembly Bottom")
	)
	(footprint ""
		(layer "B.Cu")
		(at 474.938344 -4.82092 90)
		(property "Reference" "R2U38"
			(at 0 0 90)
			(layer "B.SilkS")
			(hide yes)
			(effects
				(font
					(size 1.27 1.27)
				)
				(justify mirror)
			)
		)
		(property "Value" ""
			(at 0 0 90)
			(layer "B.Fab")
			(effects
				(font
					(size 1.27 1.27)
				)
				(justify mirror)
			)
		)
		(duplicate_pad_numbers_are_jumpers no)
		(fp_poly
			(pts
				(xy 0.2794 -0.1016) (xy -0.2794 -0.1016) (xy -0.2794 0.9906) (xy 0.2794 0.9906)
			)
			(stroke
				(width 0)
				(type default)
			)
			(fill no)
			(layer "B.CrtYd")
		)
		(fp_line
			(start 0.2794 -0.1016)
			(end 0.2794 0.9906)
			(stroke
				(width 0.1)
				(type default)
			)
			(layer "B.Fab")
		)
		(fp_line
			(start -0.2794 -0.1016)
			(end 0.2794 -0.1016)
			(stroke
				(width 0.1)
				(type default)
			)
			(layer "B.Fab")
		)
		(fp_line
			(start 0.2794 0.9906)
			(end -0.2794 0.9906)
			(stroke
				(width 0.1)
				(type default)
			)
			(layer "B.Fab")
		)
		(fp_line
			(start -0.2794 0.9906)
			(end -0.2794 -0.1016)
			(stroke
				(width 0.1)
				(type default)
			)
			(layer "B.Fab")
		)
		(pad "1" smd rect
			(at 0 0 270)
			(size 0.508 0.508)
			(layers "B.Cu" "B.Mask" "B.Paste")
			(net "P3V3_STBY")
		)
		(pad "2" smd rect
			(at 0 0.889 270)
			(size 0.508 0.508)
			(layers "B.Cu" "B.Mask" "B.Paste")
			(net "SMB_SENSOR_STBY_LVC3_SCL")
		)
		(zone
			(layer "B.Cu")
			(hatch none 0.5)
			(connect_pads
				(clearance 0)
			)
			(min_thickness 0.25)
			(keepout
				(tracks allowed)
				(vias not_allowed)
				(pads allowed)
				(copperpour not_allowed)
				(footprints allowed)
			)
			(placement
				(enabled no)
				(sheetname "")
			)
			(fill
				(thermal_gap 0.5)
				(thermal_bridge_width 0.5)
				(island_removal_mode 0)
			)
			(polygon
				(pts
					(xy 475.192344 -5.07492) (xy 475.192344 -4.56692) (xy 475.573344 -4.56692) (xy 475.573344 -5.07492)
				)
			)
		)
		(zone
			(layer "B.Cu")
			(hatch none 0.5)
			(connect_pads
				(clearance 0)
			)
			(min_thickness 0.25)
			(keepout
				(tracks not_allowed)
				(vias allowed)
				(pads allowed)
				(copperpour not_allowed)
				(footprints allowed)
			)
			(placement
				(enabled no)
				(sheetname "")
			)
			(fill
				(thermal_gap 0.5)
				(thermal_bridge_width 0.5)
				(island_removal_mode 0)
			)
			(polygon
				(pts
					(xy 475.573344 -5.07492) (xy 475.573344 -4.56692) (xy 475.192344 -4.56692) (xy 475.192344 -5.07492)
				)
			)
		)
	)
	(footprint ""
		(layer "B.Cu")
		(at 373.8372 -46.0756 -90)
		(property "Reference" "R2T60"
			(at 0 0 90)
			(layer "B.SilkS")
			(hide yes)
			(effects
				(font
					(size 1.27 1.27)
				)
				(justify mirror)
			)
		)
		(property "Value" ""
			(at 0 0 90)
			(layer "B.Fab")
			(effects
				(font
					(size 1.27 1.27)
				)
				(justify mirror)
			)
		)
		(duplicate_pad_numbers_are_jumpers no)
		(fp_poly
			(pts
				(xy 0.2794 -0.1016) (xy -0.2794 -0.1016) (xy -0.2794 0.9906) (xy 0.2794 0.9906)
			)
			(stroke
				(width 0)
				(type default)
			)
			(fill no)
			(layer "B.CrtYd")
		)
		(fp_line
			(start -0.2794 0.9906)
			(end -0.2794 -0.1016)
			(stroke
				(width 0.1)
				(type default)
			)
			(layer "B.Fab")
		)
		(fp_line
			(start 0.2794 0.9906)
			(end -0.2794 0.9906)
			(stroke
				(width 0.1)
				(type default)
			)
			(layer "B.Fab")
		)
		(fp_line
			(start -0.2794 -0.1016)
			(end 0.2794 -0.1016)
			(stroke
				(width 0.1)
				(type default)
			)
			(layer "B.Fab")
		)
		(fp_line
			(start 0.2794 -0.1016)
			(end 0.2794 0.9906)
			(stroke
				(width 0.1)
				(type default)
			)
			(layer "B.Fab")
		)
		(pad "1" smd rect
			(at 0 0 90)
			(size 0.508 0.508)
			(layers "B.Cu" "B.Mask" "B.Paste")
			(net "H_CPU0_PROCHOT_G_N")
		)
		(pad "2" smd rect
			(at 0 0.889 90)
			(size 0.508 0.508)
			(layers "B.Cu" "B.Mask" "B.Paste")
			(net "H_CPU0_PROCHOT_G_R_N")
		)
		(zone
			(layer "B.Cu")
			(hatch none 0.5)
			(connect_pads
				(clearance 0)
			)
			(min_thickness 0.25)
			(keepout
				(tracks not_allowed)
				(vias allowed)
				(pads allowed)
				(copperpour not_allowed)
				(footprints allowed)
			)
			(placement
				(enabled no)
				(sheetname "")
			)
			(fill
				(thermal_gap 0.5)
				(thermal_bridge_width 0.5)
				(island_removal_mode 0)
			)
			(polygon
				(pts
					(xy 373.2022 -45.8216) (xy 373.2022 -46.3296) (xy 373.5832 -46.3296) (xy 373.5832 -45.8216)
				)
			)
		)
		(zone
			(layer "B.Cu")
			(hatch none 0.5)
			(connect_pads
				(clearance 0)
			)
			(min_thickness 0.25)
			(keepout
				(tracks allowed)
				(vias not_allowed)
				(pads allowed)
				(copperpour not_allowed)
				(footprints allowed)
			)
			(placement
				(enabled no)
				(sheetname "")
			)
			(fill
				(thermal_gap 0.5)
				(thermal_bridge_width 0.5)
				(island_removal_mode 0)
			)
			(polygon
				(pts
					(xy 373.5832 -45.8216) (xy 373.5832 -46.3296) (xy 373.2022 -46.3296) (xy 373.2022 -45.8216)
				)
			)
		)
	)
)
